(kicad_pcb
	(version 20241229)
	(generator "pcbnew")
	(generator_version "9.0")
	(general
		(thickness 1.61)
		(legacy_teardrops no)
	)
	(paper "A3")
	(title_block
		(title "SO-DIMM DDR5 Tester")
		(date "2025-11-26")
		(rev "1.3.0")
		(comment 9 "footprints 223-227 of 627")
	)
	(layers
		(0 "F.Cu" signal)
		(4 "In1.Cu" power)
		(6 "In2.Cu" mixed)
		(8 "In3.Cu" power)
		(10 "In4.Cu" mixed)
		(12 "In5.Cu" power)
		(14 "In6.Cu" mixed)
		(16 "In7.Cu" power)
		(18 "In8.Cu" power)
		(20 "In9.Cu" mixed)
		(22 "In10.Cu" power)
		(2 "B.Cu" signal)
		(9 "F.Adhes" user "F.Adhesive")
		(11 "B.Adhes" user "B.Adhesive")
		(13 "F.Paste" user)
		(15 "B.Paste" user)
		(5 "F.SilkS" user "F.Silkscreen")
		(7 "B.SilkS" user "B.Silkscreen")
		(1 "F.Mask" user)
		(3 "B.Mask" user)
		(17 "Dwgs.User" user "User.Drawings")
		(19 "Cmts.User" user "User.Comments")
		(21 "Eco1.User" user "User.Eco1")
		(23 "Eco2.User" user "User.Eco2")
		(25 "Edge.Cuts" user)
		(27 "Margin" user)
		(31 "F.CrtYd" user "F.Courtyard")
		(29 "B.CrtYd" user "B.Courtyard")
		(35 "F.Fab" user)
		(33 "B.Fab" user)
	)
	(footprint "antmicro-footprints:C_0402_1005Metric"
		(layer "F.Cu")
		(at 176.619502 196.214503 180)
		(descr "Capacitor SMD 0402")
		(tags "capacitor SMD 0402")
		(property "Reference" "C221"
			(at 0.969502 0.614503 180)
			(layer "F.SilkS")
			(hide yes)
			(effects
				(font
					(size 0.7 0.7)
					(thickness 0.15)
				)
				(justify left bottom)
			)
		)
		(property "Value" "C_22p_0402"
			(at -1.022927 2.155213 180)
			(layer "F.Fab")
			(effects
				(font
					(size 0.7 0.7)
					(thickness 0.15)
				)
				(justify left bottom)
			)
		)
		(property "Datasheet" "https://www.yageo.com/en/Chart/Download/pdf/CC0402JRNPO9BN220"
			(at 0 0 180)
			(layer "F.Fab")
			(hide yes)
			(effects
				(font
					(size 1.27 1.27)
					(thickness 0.15)
				)
			)
		)
		(property "Author" "Antmicro"
			(at 353.239004 392.429006 0)
			(layer "F.Fab")
			(hide yes)
			(effects
				(font
					(size 1 1)
					(thickness 0.15)
				)
			)
		)
		(property "Dielectric" ""
			(at 353.239004 392.429006 0)
			(layer "F.Fab")
			(hide yes)
			(effects
				(font
					(size 1 1)
					(thickness 0.15)
				)
			)
		)
		(property "License" "Apache-2.0"
			(at 353.239004 392.429006 0)
			(layer "F.Fab")
			(hide yes)
			(effects
				(font
					(size 1 1)
					(thickness 0.15)
				)
			)
		)
		(property "MPN" "CC0402JRNPO9BN220"
			(at 353.239004 392.429006 0)
			(layer "F.Fab")
			(hide yes)
			(effects
				(font
					(size 1 1)
					(thickness 0.15)
				)
			)
		)
		(property "Manufacturer" "YAGEO"
			(at 353.239004 392.429006 0)
			(layer "F.Fab")
			(hide yes)
			(effects
				(font
					(size 1 1)
					(thickness 0.15)
				)
			)
		)
		(property "Val" "22p"
			(at 353.239004 392.429006 0)
			(layer "F.Fab")
			(hide yes)
			(effects
				(font
					(size 1 1)
					(thickness 0.15)
				)
			)
		)
		(property "Voltage" ""
			(at 353.239004 392.429006 0)
			(layer "F.Fab")
			(hide yes)
			(effects
				(font
					(size 1 1)
					(thickness 0.15)
				)
			)
		)
		(sheetname "/Supply/")
		(sheetfile "supply.kicad_sch")
		(attr smd)
		(fp_rect
			(start -0.9659 -0.481258)
			(end 0.9649 0.458742)
			(stroke
				(width 0.05)
				(type solid)
			)
			(fill no)
			(layer "F.CrtYd")
		)
		(fp_line
			(start 0.499 0.248)
			(end -0.499 0.248)
			(stroke
				(width 0.15)
				(type solid)
			)
			(layer "F.Fab")
		)
		(fp_line
			(start 0.499 -0.25)
			(end 0.499 0.248)
			(stroke
				(width 0.15)
				(type solid)
			)
			(layer "F.Fab")
		)
		(fp_line
			(start -0.499 0.248)
			(end -0.499 -0.25)
			(stroke
				(width 0.15)
				(type solid)
			)
			(layer "F.Fab")
		)
		(fp_line
			(start -0.499 -0.25)
			(end 0.499 -0.25)
			(stroke
				(width 0.15)
				(type solid)
			)
			(layer "F.Fab")
		)
		(pad "1" smd roundrect
			(at -0.484 0 180)
			(size 0.59 0.64)
			(layers "F.Cu" "F.Mask" "F.Paste")
			(roundrect_rratio 0.25)
			(net 303 "Net-(C221-Pad1)")
			(pintype "passive")
		)
		(pad "2" smd roundrect
			(at 0.484 0 180)
			(size 0.59 0.64)
			(layers "F.Cu" "F.Mask" "F.Paste")
			(roundrect_rratio 0.25)
			(net 78 "/Supply/1V0_REG")
			(pintype "passive")
		)
	)
	(footprint "antmicro-footprints:TP_SMD_1mm"
		(layer "F.Cu")
		(at 165.25 199.15)
		(property "Reference" "TP10"
			(at 0 -0.731898 0)
			(layer "F.SilkS")
			(hide yes)
			(effects
				(font
					(size 0.7 0.7)
					(thickness 0.15)
				)
				(justify left bottom)
			)
		)
		(property "Value" "TP_1mm_SMD"
			(at 0 1.4 0)
			(layer "F.Fab")
			(effects
				(font
					(size 0.7 0.7)
					(thickness 0.15)
				)
				(justify left bottom)
			)
		)
		(property "Author" "Antmicro"
			(at 0 0 0)
			(layer "F.Fab")
			(hide yes)
			(effects
				(font
					(size 1 1)
					(thickness 0.15)
				)
			)
		)
		(property "License" "Apache-2.0"
			(at 0 0 0)
			(layer "F.Fab")
			(hide yes)
			(effects
				(font
					(size 1 1)
					(thickness 0.15)
				)
			)
		)
		(property "MPN" ""
			(at 0 0 0)
			(layer "F.Fab")
			(hide yes)
			(effects
				(font
					(size 1 1)
					(thickness 0.15)
				)
			)
		)
		(property "Manufacturer" ""
			(at 0 0 0)
			(layer "F.Fab")
			(hide yes)
			(effects
				(font
					(size 1 1)
					(thickness 0.15)
				)
			)
		)
		(sheetname "/Supply/")
		(sheetfile "supply.kicad_sch")
		(attr exclude_from_pos_files)
		(pad "1" smd circle
			(at 0 0)
			(size 1 1)
			(layers "F.Cu" "F.Mask")
			(net 227 "+1V0")
			(pinfunction "1")
			(pintype "passive")
		)
	)
	(footprint "antmicro-footprints:C_0402_1005Metric"
		(layer "F.Cu")
		(at 105.175001 148.9025 180)
		(descr "Capacitor SMD 0402")
		(tags "capacitor SMD 0402")
		(property "Reference" "C7"
			(at 0 -0.699 180)
			(layer "F.SilkS")
			(hide yes)
			(effects
				(font
					(size 0.7 0.7)
					(thickness 0.15)
				)
				(justify left bottom)
			)
		)
		(property "Value" "C_4u7_0402"
			(at -1.022927 2.155213 180)
			(layer "F.Fab")
			(effects
				(font
					(size 0.7 0.7)
					(thickness 0.15)
				)
				(justify left bottom)
			)
		)
		(property "Datasheet" "https://www.murata.com/products/productdetail?partno=GRM155R61A475MEAA%23"
			(at 0 0 180)
			(layer "F.Fab")
			(hide yes)
			(effects
				(font
					(size 1.27 1.27)
					(thickness 0.15)
				)
			)
		)
		(property "Author" "Antmicro"
			(at 210.350002 297.805 0)
			(layer "F.Fab")
			(hide yes)
			(effects
				(font
					(size 1 1)
					(thickness 0.15)
				)
			)
		)
		(property "Dielectric" ""
			(at 210.350002 297.805 0)
			(layer "F.Fab")
			(hide yes)
			(effects
				(font
					(size 1 1)
					(thickness 0.15)
				)
			)
		)
		(property "License" "Apache-2.0"
			(at 210.350002 297.805 0)
			(layer "F.Fab")
			(hide yes)
			(effects
				(font
					(size 1 1)
					(thickness 0.15)
				)
			)
		)
		(property "MPN" "GRM155R61A475MEAAD"
			(at 210.350002 297.805 0)
			(layer "F.Fab")
			(hide yes)
			(effects
				(font
					(size 1 1)
					(thickness 0.15)
				)
			)
		)
		(property "Manufacturer" "Murata"
			(at 210.350002 297.805 0)
			(layer "F.Fab")
			(hide yes)
			(effects
				(font
					(size 1 1)
					(thickness 0.15)
				)
			)
		)
		(property "Val" "4u7"
			(at 210.350002 297.805 0)
			(layer "F.Fab")
			(hide yes)
			(effects
				(font
					(size 1 1)
					(thickness 0.15)
				)
			)
		)
		(property "Voltage" ""
			(at 210.350002 297.805 0)
			(layer "F.Fab")
			(hide yes)
			(effects
				(font
					(size 1 1)
					(thickness 0.15)
				)
			)
		)
		(sheetname "/DDR5 SODIMM/")
		(sheetfile "ddr5-sodimm.kicad_sch")
		(attr smd)
		(fp_rect
			(start -0.9659 -0.481258)
			(end 0.9649 0.458742)
			(stroke
				(width 0.05)
				(type solid)
			)
			(fill no)
			(layer "F.CrtYd")
		)
		(fp_line
			(start 0.499 0.248)
			(end -0.499 0.248)
			(stroke
				(width 0.15)
				(type solid)
			)
			(layer "F.Fab")
		)
		(fp_line
			(start 0.499 -0.25)
			(end 0.499 0.248)
			(stroke
				(width 0.15)
				(type solid)
			)
			(layer "F.Fab")
		)
		(fp_line
			(start -0.499 0.248)
			(end -0.499 -0.25)
			(stroke
				(width 0.15)
				(type solid)
			)
			(layer "F.Fab")
		)
		(fp_line
			(start -0.499 -0.25)
			(end 0.499 -0.25)
			(stroke
				(width 0.15)
				(type solid)
			)
			(layer "F.Fab")
		)
		(pad "1" smd roundrect
			(at -0.484 0 180)
			(size 0.59 0.64)
			(layers "F.Cu" "F.Mask" "F.Paste")
			(roundrect_rratio 0.25)
			(net 201 "+5V")
			(pintype "passive")
		)
		(pad "2" smd roundrect
			(at 0.484 0 180)
			(size 0.59 0.64)
			(layers "F.Cu" "F.Mask" "F.Paste")
			(roundrect_rratio 0.25)
			(net 1 "GND")
			(pintype "passive")
		)
	)
	(footprint "antmicro-footprints:C_0402_1005Metric"
		(layer "F.Cu")
		(at 176.119502 192.714502 -90)
		(descr "Capacitor SMD 0402")
		(tags "capacitor SMD 0402")
		(property "Reference" "C201"
			(at 0 -0.699 270)
			(layer "F.SilkS")
			(hide yes)
			(effects
				(font
					(size 0.7 0.7)
					(thickness 0.15)
				)
				(justify left bottom)
			)
		)
		(property "Value" "C_470n_0402"
			(at -1.022927 2.155213 270)
			(layer "F.Fab")
			(effects
				(font
					(size 0.7 0.7)
					(thickness 0.15)
				)
				(justify left bottom)
			)
		)
		(property "Datasheet" "https://product.tdk.com/en/search/capacitor/ceramic/mlcc/info?part_no=C1005X5R1E474M050BB"
			(at 0 0 270)
			(layer "F.Fab")
			(hide yes)
			(effects
				(font
					(size 1.27 1.27)
					(thickness 0.15)
				)
			)
		)
		(property "Author" "Antmicro"
			(at -16.595 368.834004 0)
			(layer "F.Fab")
			(hide yes)
			(effects
				(font
					(size 1 1)
					(thickness 0.15)
				)
			)
		)
		(property "Dielectric" ""
			(at -16.595 368.834004 0)
			(layer "F.Fab")
			(hide yes)
			(effects
				(font
					(size 1 1)
					(thickness 0.15)
				)
			)
		)
		(property "License" "Apache-2.0"
			(at -16.595 368.834004 0)
			(layer "F.Fab")
			(hide yes)
			(effects
				(font
					(size 1 1)
					(thickness 0.15)
				)
			)
		)
		(property "MPN" "C1005X5R1E474M050BB"
			(at -16.595 368.834004 0)
			(layer "F.Fab")
			(hide yes)
			(effects
				(font
					(size 1 1)
					(thickness 0.15)
				)
			)
		)
		(property "Manufacturer" "TDK"
			(at -16.595 368.834004 0)
			(layer "F.Fab")
			(hide yes)
			(effects
				(font
					(size 1 1)
					(thickness 0.15)
				)
			)
		)
		(property "Val" "470n"
			(at -16.595 368.834004 0)
			(layer "F.Fab")
			(hide yes)
			(effects
				(font
					(size 1 1)
					(thickness 0.15)
				)
			)
		)
		(property "Voltage" ""
			(at -16.595 368.834004 0)
			(layer "F.Fab")
			(hide yes)
			(effects
				(font
					(size 1 1)
					(thickness 0.15)
				)
			)
		)
		(sheetname "/Supply/")
		(sheetfile "supply.kicad_sch")
		(attr smd)
		(fp_rect
			(start -0.9659 -0.481258)
			(end 0.9649 0.458742)
			(stroke
				(width 0.05)
				(type solid)
			)
			(fill no)
			(layer "F.CrtYd")
		)
		(fp_line
			(start -0.499 0.248)
			(end -0.499 -0.25)
			(stroke
				(width 0.15)
				(type solid)
			)
			(layer "F.Fab")
		)
		(fp_line
			(start 0.499 0.248)
			(end -0.499 0.248)
			(stroke
				(width 0.15)
				(type solid)
			)
			(layer "F.Fab")
		)
		(fp_line
			(start -0.499 -0.25)
			(end 0.499 -0.25)
			(stroke
				(width 0.15)
				(type solid)
			)
			(layer "F.Fab")
		)
		(fp_line
			(start 0.499 -0.25)
			(end 0.499 0.248)
			(stroke
				(width 0.15)
				(type solid)
			)
			(layer "F.Fab")
		)
		(pad "1" smd roundrect
			(at -0.484 0 270)
			(size 0.59 0.64)
			(layers "F.Cu" "F.Mask" "F.Paste")
			(roundrect_rratio 0.25)
			(net 1 "GND")
			(pintype "passive")
		)
		(pad "2" smd roundrect
			(at 0.484 0 270)
			(size 0.59 0.64)
			(layers "F.Cu" "F.Mask" "F.Paste")
			(roundrect_rratio 0.25)
			(net 63 "/Supply/1V0_VCC")
			(pintype "passive")
		)
	)
	(footprint "antmicro-footprints:MicroSD_Wurth_693071020811"
		(layer "F.Cu")
		(at 74.470501 172.416 -90)
		(descr "SMT MICRO SD CARD CONNECTOR")
		(property "Reference" "J5"
			(at 9.784 5.270501 0)
			(layer "F.SilkS")
			(effects
				(font
					(size 0.7 0.7)
					(thickness 0.15)
				)
				(justify left bottom)
			)
		)
		(property "Value" "MicroSD_693071020811"
			(at 0 8.9 270)
			(layer "F.Fab")
			(effects
				(font
					(size 0.7 0.7)
					(thickness 0.15)
				)
				(justify left bottom)
			)
		)
		(property "Datasheet" "https://www.we-online.com/catalog/datasheet/693071020811.pdf"
			(at 0 0 270)
			(layer "F.Fab")
			(hide yes)
			(effects
				(font
					(size 1.27 1.27)
					(thickness 0.15)
				)
			)
		)
		(property "Author" "Antmicro"
			(at -97.945499 246.886501 0)
			(layer "F.Fab")
			(hide yes)
			(effects
				(font
					(size 1 1)
					(thickness 0.15)
				)
			)
		)
		(property "License" "Apache-2.0"
			(at -97.945499 246.886501 0)
			(layer "F.Fab")
			(hide yes)
			(effects
				(font
					(size 1 1)
					(thickness 0.15)
				)
			)
		)
		(property "MPN" "693071020811"
			(at -97.945499 246.886501 0)
			(layer "F.Fab")
			(hide yes)
			(effects
				(font
					(size 1 1)
					(thickness 0.15)
				)
			)
		)
		(property "Manufacturer" "Würth Elektronik"
			(at -97.945499 246.886501 0)
			(layer "F.Fab")
			(hide yes)
			(effects
				(font
					(size 1 1)
					(thickness 0.15)
				)
			)
		)
		(sheetname "/HDMI + SD Card/")
		(sheetfile "hdmi-sd-card.kicad_sch")
		(attr smd)
		(fp_line
			(start -7.35 1.432)
			(end -7.35 -5.267)
			(stroke
				(width 0.15)
				(type solid)
			)
			(layer "F.SilkS")
		)
		(fp_line
			(start 7.35 1.432)
			(end 7.35 -5.267)
			(stroke
				(width 0.15)
				(type solid)
			)
			(layer "F.SilkS")
		)
		(fp_line
			(start 6.201 -7.148)
			(end 2.801 -7.148)
			(stroke
				(width 0.15)
				(type solid)
			)
			(layer "F.SilkS")
		)
		(fp_circle
			(center 2.85 -7.9)
			(end 2.9 -7.9)
			(stroke
				(width 0.15)
				(type solid)
			)
			(fill yes)
			(layer "F.SilkS")
		)
		(fp_line
			(start -7.55 7.7)
			(end -7.55 4.55)
			(stroke
				(width 0.05)
				(type solid)
			)
			(layer "F.CrtYd")
		)
		(fp_line
			(start 7.5 7.7)
			(end -7.55 7.7)
			(stroke
				(width 0.05)
				(type solid)
			)
			(layer "F.CrtYd")
		)
		(fp_line
			(start 7.5 7.7)
			(end 7.5 4.55)
			(stroke
				(width 0.05)
				(type solid)
			)
			(layer "F.CrtYd")
		)
		(fp_line
			(start -8.7 4.55)
			(end -7.55 4.55)
			(stroke
				(width 0.05)
				(type solid)
			)
			(layer "F.CrtYd")
		)
		(fp_line
			(start -8.7 4.55)
			(end -8.7 1.6)
			(stroke
				(width 0.05)
				(type solid)
			)
			(layer "F.CrtYd")
		)
		(fp_line
			(start 8.7 4.55)
			(end 7.5 4.55)
			(stroke
				(width 0.05)
				(type solid)
			)
			(layer "F.CrtYd")
		)
		(fp_line
			(start 8.7 4.55)
			(end 8.7 1.6)
			(stroke
				(width 0.05)
				(type solid)
			)
			(layer "F.CrtYd")
		)
		(fp_line
			(start -7.55 1.6)
			(end -8.7 1.6)
			(stroke
				(width 0.05)
				(type solid)
			)
			(layer "F.CrtYd")
		)
		(fp_line
			(start 7.5 1.6)
			(end 8.7 1.6)
			(stroke
				(width 0.05)
				(type solid)
			)
			(layer "F.CrtYd")
		)
		(fp_line
			(start 7.5 1.6)
			(end 7.5 -5.45)
			(stroke
				(width 0.05)
				(type solid)
			)
			(layer "F.CrtYd")
		)
		(fp_line
			(start -7.55 -5.45)
			(end -7.55 1.6)
			(stroke
				(width 0.05)
				(type solid)
			)
			(layer "F.CrtYd")
		)
		(fp_line
			(start -7.55 -5.45)
			(end -9.1 -5.45)
			(stroke
				(width 0.05)
				(type solid)
			)
			(layer "F.CrtYd")
		)
		(fp_line
			(start 7.5 -5.45)
			(end 8.4 -5.45)
			(stroke
				(width 0.05)
				(type solid)
			)
			(layer "F.CrtYd")
		)
		(fp_line
			(start -9.1 -7.6)
			(end -9.1 -5.45)
			(stroke
				(width 0.05)
				(type solid)
			)
			(layer "F.CrtYd")
		)
		(fp_line
			(start -9.1 -7.6)
			(end -7.05 -7.6)
			(stroke
				(width 0.05)
				(type solid)
			)
			(layer "F.CrtYd")
		)
		(fp_line
			(start 2.75 -7.6)
			(end 2.75 -8.7)
			(stroke
				(width 0.05)
				(type solid)
			)
			(layer "F.CrtYd")
		)
		(fp_line
			(start 8.4 -7.6)
			(end 8.4 -5.45)
			(stroke
				(width 0.05)
				(type solid)
			)
			(layer "F.CrtYd")
		)
		(fp_line
			(start 8.4 -7.6)
			(end 2.75 -7.6)
			(stroke
				(width 0.05)
				(type solid)
			)
			(layer "F.CrtYd")
		)
		(fp_line
			(start -7.05 -8.7)
			(end -7.05 -7.6)
			(stroke
				(width 0.05)
				(type solid)
			)
			(layer "F.CrtYd")
		)
		(fp_line
			(start -7.05 -8.7)
			(end 2.75 -8.7)
			(stroke
				(width 0.05)
				(type solid)
			)
			(layer "F.CrtYd")
		)
		(fp_line
			(start -7.35 7.502)
			(end 7.35 7.502)
			(stroke
				(width 0.15)
				(type solid)
			)
			(layer "F.Fab")
		)
		(fp_line
			(start 7.35 7.353)
			(end 7.35 -7.148)
			(stroke
				(width 0.15)
				(type solid)
			)
			(layer "F.Fab")
		)
		(fp_line
			(start -7.35 -7.148)
			(end -7.35 7.353)
			(stroke
				(width 0.15)
				(type solid)
			)
			(layer "F.Fab")
		)
		(fp_line
			(start 7.35 -7.148)
			(end -7.35 -7.148)
			(stroke
				(width 0.15)
				(type solid)
			)
			(layer "F.Fab")
		)
		(pad "" np_thru_hole circle
			(at -4.95 3.485 270)
			(size 1 1)
			(drill 1)
			(layers "*.Cu" "*.Mask")
		)
		(pad "" np_thru_hole oval
			(at 3.05 3.485 270)
			(size 1.7 1)
			(drill oval 1.7 1)
			(layers "*.Cu" "*.Mask")
		)
		(pad "1" smd rect
			(at 2.25 -7.57 270)
			(size 0.7 1.9)
			(layers "F.Cu" "F.Mask" "F.Paste")
			(net 350 "/FPGA bank 16/SD.DAT2")
			(pinfunction "DAT2")
			(pintype "bidirectional")
		)
		(pad "2" smd rect
			(at 1.15 -7.57 270)
			(size 0.7 1.9)
			(layers "F.Cu" "F.Mask" "F.Paste")
			(net 371 "/FPGA bank 16/SD.DAT3")
			(pinfunction "DAT3/CD")
			(pintype "bidirectional")
		)
		(pad "3" smd rect
			(at 0.05 -7.57 270)
			(size 0.7 1.9)
			(layers "F.Cu" "F.Mask" "F.Paste")
			(net 372 "/FPGA bank 16/SD.CMD")
			(pinfunction "CMD")
			(pintype "input")
		)
		(pad "4" smd rect
			(at -1.05 -7.57 270)
			(size 0.7 1.9)
			(layers "F.Cu" "F.Mask" "F.Paste")
			(net 200 "+3V3")
			(pinfunction "VDD")
			(pintype "power_in")
		)
		(pad "5" smd rect
			(at -2.15 -7.57 270)
			(size 0.7 1.9)
			(layers "F.Cu" "F.Mask" "F.Paste")
			(net 373 "/FPGA bank 16/SD.CLK")
			(pinfunction "CLK")
			(pintype "input")
		)
		(pad "6" smd rect
			(at -3.25 -7.57 270)
			(size 0.7 1.9)
			(layers "F.Cu" "F.Mask" "F.Paste")
			(net 1 "GND")
			(pinfunction "VSS")
			(pintype "passive")
		)
		(pad "7" smd rect
			(at -4.35 -7.57 270)
			(size 0.7 1.9)
			(layers "F.Cu" "F.Mask" "F.Paste")
			(net 374 "/FPGA bank 16/SD.DAT0")
			(pinfunction "DAT0")
			(pintype "input")
		)
		(pad "8" smd rect
			(at -5.45 -7.57 270)
			(size 0.7 1.9)
			(layers "F.Cu" "F.Mask" "F.Paste")
			(net 594 "/FPGA bank 16/SD.DAT1")
			(pinfunction "DAT1")
			(pintype "input")
		)
		(pad "9" smd rect
			(at -6.55 -7.57 270)
			(size 0.7 1.9)
			(layers "F.Cu" "F.Mask" "F.Paste")
			(net 330 "Net-(J5-CD_SW1)")
			(pinfunction "CD_SW1")
			(pintype "passive")
		)
		(pad "SH" smd rect
			(at -8.1 -6.515 270)
			(size 1.7 1.8)
			(layers "F.Cu" "F.Mask" "F.Paste")
			(net 1 "GND")
			(pinfunction "SH")
			(pintype "passive")
		)
		(pad "SH" smd rect
			(at -7.85 3.08 270)
			(size 1.4 2.6)
			(layers "F.Cu" "F.Mask" "F.Paste")
			(net 1 "GND")
			(pinfunction "SH")
			(pintype "passive")
		)
		(pad "SH" smd rect
			(at 7.4 -6.515 270)
			(size 1.7 1.8)
			(layers "F.Cu" "F.Mask" "F.Paste")
			(net 1 "GND")
			(pinfunction "SH")
			(pintype "passive")
		)
		(pad "SH" smd rect
			(at 7.85 3.08 270)
			(size 1.4 2.6)
			(layers "F.Cu" "F.Mask" "F.Paste")
			(net 1 "GND")
			(pinfunction "SH")
			(pintype "passive")
		)
	)
)
